(kicad_pcb
	(version 20260206)
	(generator "pcbnew")
	(generator_version "10.0")
	(general
		(thickness 1.6)
		(legacy_teardrops no)
	)
	(paper "A4")
	(title_block
		(title "04192023_DAF0TMB3IC0_F0TG_MB_C_brd_V02_OCP.brd")
		(comment 1 "Grand Teton / footprints 5857-5863 of 8354")
	)
	(layers
		(0 "F.Cu" signal "TOP")
		(4 "In1.Cu" signal "GND")
		(6 "In2.Cu" signal "IN1")
		(8 "In3.Cu" signal "GND1")
		(10 "In4.Cu" signal "IN2")
		(12 "In5.Cu" signal "GND2")
		(14 "In6.Cu" signal "IN3")
		(16 "In7.Cu" signal "GND3")
		(18 "In8.Cu" signal "VCC")
		(20 "In9.Cu" signal "VCC1")
		(22 "In10.Cu" signal "GND4")
		(24 "In11.Cu" signal "IN4")
		(26 "In12.Cu" signal "GND5")
		(28 "In13.Cu" signal "IN5")
		(30 "In14.Cu" signal "GND6")
		(32 "In15.Cu" signal "IN6")
		(34 "In16.Cu" signal "GND7")
		(2 "B.Cu" signal "BOTTOM")
		(9 "F.Adhes" user "F.Adhesive")
		(11 "B.Adhes" user "B.Adhesive")
		(13 "F.Paste" user "Package Geometry/Pastemask Top")
		(15 "B.Paste" user "Package Geometry/Pastemask Bottom")
		(5 "F.SilkS" user "Ref Des/Silkscreen Top")
		(7 "B.SilkS" user "Ref Des/Silkscreen Bottom")
		(1 "F.Mask" user "Board Geometry/Soldermask Top")
		(3 "B.Mask" user "Board Geometry/Soldermask Bottom")
		(17 "Dwgs.User" user "User.Drawings")
		(19 "Cmts.User" user "User.Comments")
		(21 "Eco1.User" user "User.Eco1")
		(23 "Eco2.User" user "User.Eco2")
		(25 "Edge.Cuts" user "Board Geometry/Outline")
		(27 "Margin" user)
		(31 "F.CrtYd" user "Package Geometry/Place Bound Top")
		(29 "B.CrtYd" user "Package Geometry/Place Bound Bottom")
		(35 "F.Fab" user "Ref Des/Assembly Top")
		(33 "B.Fab" user "Ref Des/Assembly Bottom")
	)
	(footprint ""
		(layer "B.Cu")
		(at 402.322538 -322.170552)
		(property "Reference" "R5027"
			(at 0 0 0)
			(layer "B.SilkS")
			(hide yes)
			(effects
				(font
					(size 1.27 1.27)
				)
				(justify mirror)
			)
		)
		(property "Value" ""
			(at 0 0 0)
			(layer "B.Fab")
			(effects
				(font
					(size 1.27 1.27)
				)
				(justify mirror)
			)
		)
		(duplicate_pad_numbers_are_jumpers no)
		(fp_line
			(start -0.7874 -0.4064)
			(end -0.7874 0.4064)
			(stroke
				(width 0.1524)
				(type default)
			)
			(layer "B.SilkS")
		)
		(fp_line
			(start -0.7874 0.4064)
			(end 0.7874 0.4064)
			(stroke
				(width 0.1524)
				(type default)
			)
			(layer "B.SilkS")
		)
		(fp_line
			(start 0.7874 -0.4064)
			(end -0.7874 -0.4064)
			(stroke
				(width 0.1524)
				(type default)
			)
			(layer "B.SilkS")
		)
		(fp_line
			(start 0.7874 0.4064)
			(end 0.7874 -0.4064)
			(stroke
				(width 0.1524)
				(type default)
			)
			(layer "B.SilkS")
		)
		(fp_line
			(start -0.67945 -0.3048)
			(end -0.67945 0.3048)
			(stroke
				(width 0.1)
				(type default)
			)
			(layer "B.Fab")
		)
		(fp_line
			(start -0.67945 0.3048)
			(end -0.120396 0.3048)
			(stroke
				(width 0.1)
				(type default)
			)
			(layer "B.Fab")
		)
		(fp_line
			(start -0.12065 -0.3048)
			(end -0.67945 -0.3048)
			(stroke
				(width 0.1)
				(type default)
			)
			(layer "B.Fab")
		)
		(fp_line
			(start -0.12065 -0.2794)
			(end -0.12065 -0.3048)
			(stroke
				(width 0.1)
				(type default)
			)
			(layer "B.Fab")
		)
		(fp_line
			(start -0.120396 0.2794)
			(end 0.12065 0.2794)
			(stroke
				(width 0.1)
				(type default)
			)
			(layer "B.Fab")
		)
		(fp_line
			(start -0.120396 0.3048)
			(end -0.120396 0.2794)
			(stroke
				(width 0.1)
				(type default)
			)
			(layer "B.Fab")
		)
		(fp_line
			(start 0.12065 -0.305054)
			(end 0.12065 -0.2794)
			(stroke
				(width 0.1)
				(type default)
			)
			(layer "B.Fab")
		)
		(fp_line
			(start 0.12065 -0.2794)
			(end -0.12065 -0.2794)
			(stroke
				(width 0.1)
				(type default)
			)
			(layer "B.Fab")
		)
		(fp_line
			(start 0.12065 0.2794)
			(end 0.12065 0.3048)
			(stroke
				(width 0.1)
				(type default)
			)
			(layer "B.Fab")
		)
		(fp_line
			(start 0.12065 0.3048)
			(end 0.67945 0.3048)
			(stroke
				(width 0.1)
				(type default)
			)
			(layer "B.Fab")
		)
		(fp_line
			(start 0.67945 -0.305054)
			(end 0.12065 -0.305054)
			(stroke
				(width 0.1)
				(type default)
			)
			(layer "B.Fab")
		)
		(fp_line
			(start 0.67945 0.3048)
			(end 0.67945 -0.305054)
			(stroke
				(width 0.1)
				(type default)
			)
			(layer "B.Fab")
		)
		(pad "1" smd circle
			(at 0.40005 0 180)
			(size 0 0)
			(layers "B.Cu" "B.Mask" "B.Paste")
			(net "GND")
		)
		(pad "2" smd circle
			(at -0.40005 0 180)
			(size 0 0)
			(layers "B.Cu" "B.Mask" "B.Paste")
			(net "IRQ_SMI_ACTIVE_N")
		)
	)
	(footprint ""
		(layer "B.Cu")
		(at 320.571876 -66.708782 90)
		(property "Reference" "R3075"
			(at 0 0 90)
			(layer "B.SilkS")
			(hide yes)
			(effects
				(font
					(size 1.27 1.27)
				)
				(justify mirror)
			)
		)
		(property "Value" ""
			(at 0 0 90)
			(layer "B.Fab")
			(effects
				(font
					(size 1.27 1.27)
				)
				(justify mirror)
			)
		)
		(duplicate_pad_numbers_are_jumpers no)
		(fp_line
			(start 0.7874 -0.4064)
			(end -0.7874 -0.4064)
			(stroke
				(width 0.1524)
				(type default)
			)
			(layer "B.SilkS")
		)
		(fp_line
			(start -0.7874 -0.4064)
			(end -0.7874 0.4064)
			(stroke
				(width 0.1524)
				(type default)
			)
			(layer "B.SilkS")
		)
		(fp_line
			(start 0.7874 0.4064)
			(end 0.7874 -0.4064)
			(stroke
				(width 0.1524)
				(type default)
			)
			(layer "B.SilkS")
		)
		(fp_line
			(start -0.7874 0.4064)
			(end 0.7874 0.4064)
			(stroke
				(width 0.1524)
				(type default)
			)
			(layer "B.SilkS")
		)
		(fp_line
			(start 0.67945 -0.305054)
			(end 0.12065 -0.305054)
			(stroke
				(width 0.1)
				(type default)
			)
			(layer "B.Fab")
		)
		(fp_line
			(start 0.12065 -0.305054)
			(end 0.12065 -0.2794)
			(stroke
				(width 0.1)
				(type default)
			)
			(layer "B.Fab")
		)
		(fp_line
			(start -0.12065 -0.3048)
			(end -0.67945 -0.3048)
			(stroke
				(width 0.1)
				(type default)
			)
			(layer "B.Fab")
		)
		(fp_line
			(start -0.67945 -0.3048)
			(end -0.67945 0.3048)
			(stroke
				(width 0.1)
				(type default)
			)
			(layer "B.Fab")
		)
		(fp_line
			(start 0.12065 -0.2794)
			(end -0.12065 -0.2794)
			(stroke
				(width 0.1)
				(type default)
			)
			(layer "B.Fab")
		)
		(fp_line
			(start -0.12065 -0.2794)
			(end -0.12065 -0.3048)
			(stroke
				(width 0.1)
				(type default)
			)
			(layer "B.Fab")
		)
		(fp_line
			(start 0.12065 0.2794)
			(end 0.12065 0.3048)
			(stroke
				(width 0.1)
				(type default)
			)
			(layer "B.Fab")
		)
		(fp_line
			(start -0.120396 0.2794)
			(end 0.12065 0.2794)
			(stroke
				(width 0.1)
				(type default)
			)
			(layer "B.Fab")
		)
		(fp_line
			(start 0.67945 0.3048)
			(end 0.67945 -0.305054)
			(stroke
				(width 0.1)
				(type default)
			)
			(layer "B.Fab")
		)
		(fp_line
			(start 0.12065 0.3048)
			(end 0.67945 0.3048)
			(stroke
				(width 0.1)
				(type default)
			)
			(layer "B.Fab")
		)
		(fp_line
			(start -0.120396 0.3048)
			(end -0.120396 0.2794)
			(stroke
				(width 0.1)
				(type default)
			)
			(layer "B.Fab")
		)
		(fp_line
			(start -0.67945 0.3048)
			(end -0.120396 0.3048)
			(stroke
				(width 0.1)
				(type default)
			)
			(layer "B.Fab")
		)
		(pad "1" smd circle
			(at 0.40005 0 270)
			(size 0 0)
			(layers "B.Cu" "B.Mask" "B.Paste")
			(net "LED_PWRGD_PS_PWROK_PLD")
		)
		(pad "2" smd circle
			(at -0.40005 0 270)
			(size 0 0)
			(layers "B.Cu" "B.Mask" "B.Paste")
			(net "P3V3_AUX")
		)
	)
	(footprint ""
		(layer "B.Cu")
		(at 62.563248 -168.86682 -90)
		(property "Reference" "PC132_6"
			(at 0 0 90)
			(layer "B.SilkS")
			(hide yes)
			(effects
				(font
					(size 1.27 1.27)
				)
				(justify mirror)
			)
		)
		(property "Value" ""
			(at 0 0 90)
			(layer "B.Fab")
			(effects
				(font
					(size 1.27 1.27)
				)
				(justify mirror)
			)
		)
		(duplicate_pad_numbers_are_jumpers no)
		(fp_line
			(start -1.524 0.762)
			(end 1.524 0.762)
			(stroke
				(width 0.1524)
				(type default)
			)
			(layer "B.SilkS")
		)
		(fp_line
			(start 1.524 0.762)
			(end 1.524 -0.762)
			(stroke
				(width 0.1524)
				(type default)
			)
			(layer "B.SilkS")
		)
		(fp_line
			(start -1.524 -0.762)
			(end -1.524 0.762)
			(stroke
				(width 0.1524)
				(type default)
			)
			(layer "B.SilkS")
		)
		(fp_line
			(start 1.524 -0.762)
			(end -1.524 -0.762)
			(stroke
				(width 0.1524)
				(type default)
			)
			(layer "B.SilkS")
		)
		(fp_line
			(start -1.1049 0.724916)
			(end -1.1049 -0.724916)
			(stroke
				(width 0.1)
				(type default)
			)
			(layer "B.Fab")
		)
		(fp_line
			(start 1.1049 0.724916)
			(end -1.1049 0.724916)
			(stroke
				(width 0.1)
				(type default)
			)
			(layer "B.Fab")
		)
		(fp_line
			(start -1.1049 -0.724916)
			(end 1.1049 -0.724916)
			(stroke
				(width 0.1)
				(type default)
			)
			(layer "B.Fab")
		)
		(fp_line
			(start 1.1049 -0.724916)
			(end 1.1049 0.724916)
			(stroke
				(width 0.1)
				(type default)
			)
			(layer "B.Fab")
		)
		(pad "1" smd rect
			(at 0.889 0 270)
			(size 1.016 1.27)
			(layers "B.Cu" "B.Mask" "B.Paste")
			(net "SW_P12V_AUX_PVDDCR_CPU0_P1_FLT")
		)
		(pad "2" smd rect
			(at -0.889 0 270)
			(size 1.016 1.27)
			(layers "B.Cu" "B.Mask" "B.Paste")
			(net "GND")
		)
	)
	(footprint ""
		(layer "B.Cu")
		(at 372.400322 -416.899344 90)
		(property "Reference" "C6598"
			(at 0 0 90)
			(layer "B.SilkS")
			(hide yes)
			(effects
				(font
					(size 1.27 1.27)
				)
				(justify mirror)
			)
		)
		(property "Value" ""
			(at 0 0 90)
			(layer "B.Fab")
			(effects
				(font
					(size 1.27 1.27)
				)
				(justify mirror)
			)
		)
		(duplicate_pad_numbers_are_jumpers no)
		(fp_line
			(start 0.299974 -0.150114)
			(end -0.299974 -0.150114)
			(stroke
				(width 0.1)
				(type default)
			)
			(layer "B.Fab")
		)
		(fp_line
			(start -0.299974 -0.150114)
			(end -0.299974 0.150114)
			(stroke
				(width 0.1)
				(type default)
			)
			(layer "B.Fab")
		)
		(fp_line
			(start 0.299974 0.150114)
			(end 0.299974 -0.150114)
			(stroke
				(width 0.1)
				(type default)
			)
			(layer "B.Fab")
		)
		(fp_line
			(start -0.299974 0.150114)
			(end 0.299974 0.150114)
			(stroke
				(width 0.1)
				(type default)
			)
			(layer "B.Fab")
		)
		(pad "1" smd rect
			(at 0.2667 0 270)
			(size 0.3048 0.381)
			(layers "B.Cu" "B.Mask" "B.Paste")
			(net "P5E_CPU0_P3_TX_BUF_C_DN<0>")
		)
		(pad "2" smd rect
			(at -0.2667 0 270)
			(size 0.3048 0.381)
			(layers "B.Cu" "B.Mask" "B.Paste")
			(net "P5E_CPU0_P3_TX_BUF_DN<0>")
		)
	)
	(footprint ""
		(layer "B.Cu")
		(at 454.02246 -11.705844)
		(property "Reference" "R38"
			(at 0 0 0)
			(layer "B.SilkS")
			(hide yes)
			(effects
				(font
					(size 1.27 1.27)
				)
				(justify mirror)
			)
		)
		(property "Value" ""
			(at 0 0 0)
			(layer "B.Fab")
			(effects
				(font
					(size 1.27 1.27)
				)
				(justify mirror)
			)
		)
		(duplicate_pad_numbers_are_jumpers no)
		(fp_line
			(start -0.7874 -0.4064)
			(end -0.7874 0.4064)
			(stroke
				(width 0.1524)
				(type default)
			)
			(layer "B.SilkS")
		)
		(fp_line
			(start -0.7874 0.4064)
			(end 0.7874 0.4064)
			(stroke
				(width 0.1524)
				(type default)
			)
			(layer "B.SilkS")
		)
		(fp_line
			(start 0.7874 -0.4064)
			(end -0.7874 -0.4064)
			(stroke
				(width 0.1524)
				(type default)
			)
			(layer "B.SilkS")
		)
		(fp_line
			(start 0.7874 0.4064)
			(end 0.7874 -0.4064)
			(stroke
				(width 0.1524)
				(type default)
			)
			(layer "B.SilkS")
		)
		(fp_line
			(start -0.67945 -0.3048)
			(end -0.67945 0.3048)
			(stroke
				(width 0.1)
				(type default)
			)
			(layer "B.Fab")
		)
		(fp_line
			(start -0.67945 0.3048)
			(end -0.120396 0.3048)
			(stroke
				(width 0.1)
				(type default)
			)
			(layer "B.Fab")
		)
		(fp_line
			(start -0.12065 -0.3048)
			(end -0.67945 -0.3048)
			(stroke
				(width 0.1)
				(type default)
			)
			(layer "B.Fab")
		)
		(fp_line
			(start -0.12065 -0.2794)
			(end -0.12065 -0.3048)
			(stroke
				(width 0.1)
				(type default)
			)
			(layer "B.Fab")
		)
		(fp_line
			(start -0.120396 0.2794)
			(end 0.12065 0.2794)
			(stroke
				(width 0.1)
				(type default)
			)
			(layer "B.Fab")
		)
		(fp_line
			(start -0.120396 0.3048)
			(end -0.120396 0.2794)
			(stroke
				(width 0.1)
				(type default)
			)
			(layer "B.Fab")
		)
		(fp_line
			(start 0.12065 -0.305054)
			(end 0.12065 -0.2794)
			(stroke
				(width 0.1)
				(type default)
			)
			(layer "B.Fab")
		)
		(fp_line
			(start 0.12065 -0.2794)
			(end -0.12065 -0.2794)
			(stroke
				(width 0.1)
				(type default)
			)
			(layer "B.Fab")
		)
		(fp_line
			(start 0.12065 0.2794)
			(end 0.12065 0.3048)
			(stroke
				(width 0.1)
				(type default)
			)
			(layer "B.Fab")
		)
		(fp_line
			(start 0.12065 0.3048)
			(end 0.67945 0.3048)
			(stroke
				(width 0.1)
				(type default)
			)
			(layer "B.Fab")
		)
		(fp_line
			(start 0.67945 -0.305054)
			(end 0.12065 -0.305054)
			(stroke
				(width 0.1)
				(type default)
			)
			(layer "B.Fab")
		)
		(fp_line
			(start 0.67945 0.3048)
			(end 0.67945 -0.305054)
			(stroke
				(width 0.1)
				(type default)
			)
			(layer "B.Fab")
		)
		(pad "1" smd circle
			(at 0.40005 0 180)
			(size 0 0)
			(layers "B.Cu" "B.Mask" "B.Paste")
			(net "OCP_SFF_MAIN_PWR_EN")
		)
		(pad "2" smd circle
			(at -0.40005 0 180)
			(size 0 0)
			(layers "B.Cu" "B.Mask" "B.Paste")
			(net "OCP_SFF_MAIN_PWR_EN_R")
		)
	)
	(footprint ""
		(layer "B.Cu")
		(at 91.493594 -301.716948 180)
		(property "Reference" "R521"
			(at 0 0 0)
			(layer "B.SilkS")
			(hide yes)
			(effects
				(font
					(size 1.27 1.27)
				)
				(justify mirror)
			)
		)
		(property "Value" ""
			(at 0 0 0)
			(layer "B.Fab")
			(effects
				(font
					(size 1.27 1.27)
				)
				(justify mirror)
			)
		)
		(duplicate_pad_numbers_are_jumpers no)
		(fp_line
			(start 0.7874 0.4064)
			(end 0.7874 -0.4064)
			(stroke
				(width 0.1524)
				(type default)
			)
			(layer "B.SilkS")
		)
		(fp_line
			(start 0.7874 -0.4064)
			(end -0.7874 -0.4064)
			(stroke
				(width 0.1524)
				(type default)
			)
			(layer "B.SilkS")
		)
		(fp_line
			(start -0.7874 0.4064)
			(end 0.7874 0.4064)
			(stroke
				(width 0.1524)
				(type default)
			)
			(layer "B.SilkS")
		)
		(fp_line
			(start -0.7874 -0.4064)
			(end -0.7874 0.4064)
			(stroke
				(width 0.1524)
				(type default)
			)
			(layer "B.SilkS")
		)
		(fp_line
			(start 0.67945 0.3048)
			(end 0.67945 -0.305054)
			(stroke
				(width 0.1)
				(type default)
			)
			(layer "B.Fab")
		)
		(fp_line
			(start 0.67945 -0.305054)
			(end 0.12065 -0.305054)
			(stroke
				(width 0.1)
				(type default)
			)
			(layer "B.Fab")
		)
		(fp_line
			(start 0.12065 0.3048)
			(end 0.67945 0.3048)
			(stroke
				(width 0.1)
				(type default)
			)
			(layer "B.Fab")
		)
		(fp_line
			(start 0.12065 0.2794)
			(end 0.12065 0.3048)
			(stroke
				(width 0.1)
				(type default)
			)
			(layer "B.Fab")
		)
		(fp_line
			(start 0.12065 -0.2794)
			(end -0.12065 -0.2794)
			(stroke
				(width 0.1)
				(type default)
			)
			(layer "B.Fab")
		)
		(fp_line
			(start 0.12065 -0.305054)
			(end 0.12065 -0.2794)
			(stroke
				(width 0.1)
				(type default)
			)
			(layer "B.Fab")
		)
		(fp_line
			(start -0.120396 0.3048)
			(end -0.120396 0.2794)
			(stroke
				(width 0.1)
				(type default)
			)
			(layer "B.Fab")
		)
		(fp_line
			(start -0.120396 0.2794)
			(end 0.12065 0.2794)
			(stroke
				(width 0.1)
				(type default)
			)
			(layer "B.Fab")
		)
		(fp_line
			(start -0.12065 -0.2794)
			(end -0.12065 -0.3048)
			(stroke
				(width 0.1)
				(type default)
			)
			(layer "B.Fab")
		)
		(fp_line
			(start -0.12065 -0.3048)
			(end -0.67945 -0.3048)
			(stroke
				(width 0.1)
				(type default)
			)
			(layer "B.Fab")
		)
		(fp_line
			(start -0.67945 0.3048)
			(end -0.120396 0.3048)
			(stroke
				(width 0.1)
				(type default)
			)
			(layer "B.Fab")
		)
		(fp_line
			(start -0.67945 -0.3048)
			(end -0.67945 0.3048)
			(stroke
				(width 0.1)
				(type default)
			)
			(layer "B.Fab")
		)
		(pad "1" smd circle
			(at 0.40005 0)
			(size 0 0)
			(layers "B.Cu" "B.Mask" "B.Paste")
			(net "CPU1_SA1")
		)
		(pad "2" smd circle
			(at -0.40005 0)
			(size 0 0)
			(layers "B.Cu" "B.Mask" "B.Paste")
			(net "GND")
		)
	)
	(footprint ""
		(layer "B.Cu")
		(at 125.800866 -156.378148 -90)
		(property "Reference" "PC8011"
			(at 0 0 90)
			(layer "B.SilkS")
			(hide yes)
			(effects
				(font
					(size 1.27 1.27)
				)
				(justify mirror)
			)
		)
		(property "Value" ""
			(at 0 0 90)
			(layer "B.Fab")
			(effects
				(font
					(size 1.27 1.27)
				)
				(justify mirror)
			)
		)
		(duplicate_pad_numbers_are_jumpers no)
		(fp_line
			(start -1.524 0.762)
			(end 1.524 0.762)
			(stroke
				(width 0.1524)
				(type default)
			)
			(layer "B.SilkS")
		)
		(fp_line
			(start 1.524 0.762)
			(end 1.524 -0.762)
			(stroke
				(width 0.1524)
				(type default)
			)
			(layer "B.SilkS")
		)
		(fp_line
			(start -1.524 -0.762)
			(end -1.524 0.762)
			(stroke
				(width 0.1524)
				(type default)
			)
			(layer "B.SilkS")
		)
		(fp_line
			(start 1.524 -0.762)
			(end -1.524 -0.762)
			(stroke
				(width 0.1524)
				(type default)
			)
			(layer "B.SilkS")
		)
		(fp_line
			(start -1.1049 0.724916)
			(end -1.1049 -0.724916)
			(stroke
				(width 0.1)
				(type default)
			)
			(layer "B.Fab")
		)
		(fp_line
			(start 1.1049 0.724916)
			(end -1.1049 0.724916)
			(stroke
				(width 0.1)
				(type default)
			)
			(layer "B.Fab")
		)
		(fp_line
			(start -1.1049 -0.724916)
			(end 1.1049 -0.724916)
			(stroke
				(width 0.1)
				(type default)
			)
			(layer "B.Fab")
		)
		(fp_line
			(start 1.1049 -0.724916)
			(end 1.1049 0.724916)
			(stroke
				(width 0.1)
				(type default)
			)
			(layer "B.Fab")
		)
		(pad "1" smd rect
			(at 0.889 0 270)
			(size 1.016 1.27)
			(layers "B.Cu" "B.Mask" "B.Paste")
			(net "SW_P12V_AUX_PVDDCR_SOC_P1_FLT")
		)
		(pad "2" smd rect
			(at -0.889 0 270)
			(size 1.016 1.27)
			(layers "B.Cu" "B.Mask" "B.Paste")
			(net "GND")
		)
	)
)
